(kicad_pcb
	(version 20260206)
	(generator "pcbnew")
	(generator_version "10.0")
	(general
		(thickness 1.6)
		(legacy_teardrops no)
	)
	(paper "A4")
	(title_block
		(title "panther-plus-userver — 13130-1b_20150205.brd")
		(comment 1 "Honey Badger (Wiwynn) / footprint 1214 of 1509 (DIMM3), pads 149-155 of 210")
	)
	(layers
		(0 "F.Cu" signal "TOP")
		(4 "In1.Cu" signal "L2")
		(6 "In2.Cu" signal "L3")
		(8 "In3.Cu" signal "L4")
		(10 "In4.Cu" signal "L5")
		(12 "In5.Cu" signal "L6")
		(14 "In6.Cu" signal "L7")
		(16 "In7.Cu" signal "L8")
		(18 "In8.Cu" signal "L9")
		(20 "In9.Cu" signal "L10")
		(22 "In10.Cu" signal "L11")
		(2 "B.Cu" signal "BOTTOM")
		(9 "F.Adhes" user "F.Adhesive")
		(11 "B.Adhes" user "B.Adhesive")
		(13 "F.Paste" user "Package Geometry/Pastemask Top")
		(15 "B.Paste" user "Package Geometry/Pastemask Bottom")
		(5 "F.SilkS" user "Ref Des/Silkscreen Top")
		(7 "B.SilkS" user "Ref Des/Silkscreen Bottom")
		(1 "F.Mask" user "Board Geometry/Soldermask Top")
		(3 "B.Mask" user "Board Geometry/Soldermask Bottom")
		(17 "Dwgs.User" user "User.Drawings")
		(19 "Cmts.User" user "User.Comments")
		(21 "Eco1.User" user "User.Eco1")
		(23 "Eco2.User" user "User.Eco2")
		(25 "Edge.Cuts" user "Board Geometry/Outline")
		(27 "Margin" user)
		(31 "F.CrtYd" user "Package Geometry/Place Bound Top")
		(29 "B.CrtYd" user "Package Geometry/Place Bound Bottom")
		(35 "F.Fab" user "Ref Des/Assembly Top")
		(33 "B.Fab" user "Ref Des/Assembly Bottom")
	)
	(footprint ""
		(layer "B.Cu")
		(at 159.999934 -5.790692)
		(property "Reference" "DIMM3"
			(at 0 0 0)
			(layer "B.SilkS")
			(hide yes)
			(effects
				(font
					(size 1.27 1.27)
				)
				(justify mirror)
			)
		)
		(property "Value" "DDR3-204P-142-COLAY-1-GP-U"
			(at 41.312338 -16.676878 0)
			(unlocked yes)
			(layer "B.Fab")
			(hide yes)
			(effects
				(font
					(size 1.016 1.016)
					(thickness 0.1524)
				)
				(justify mirror)
			)
		)
		(property "Device Type" "AS0A626-J8R6-7H-COLAY-1"
			(at 41.312338 -18.200878 0)
			(unlocked yes)
			(layer "B.Fab")
			(hide yes)
			(effects
				(font
					(size 1.016 1.016)
					(thickness 0.1524)
				)
				(justify mirror)
			)
		)
		(duplicate_pad_numbers_are_jumpers no)
		(pad "147" smd custom
			(at 14.549882 -4.100068 180)
			(size 0.1143 0.1143)
			(layers "B.Cu" "B.Mask" "B.Paste")
			(net "M_B_DQ35")
			(options
				(clearance outline)
				(anchor circle)
			)
			(primitives
				(gr_poly
					(pts
						(xy 0 -0.9017) (xy -0.03175 -0.89916) (xy -0.0635 -0.889) (xy -0.09144 -0.87376) (xy -0.11684 -0.85344)
						(xy -0.13716 -0.82804) (xy -0.1524 -0.8001) (xy -0.16256 -0.76835) (xy -0.1651 -0.7366) (xy -0.1651 -0.19685)
						(xy -0.17272 -0.18923) (xy -0.17907 -0.18034) (xy -0.18669 -0.17145) (xy -0.19177 -0.16256) (xy -0.19812 -0.15367)
						(xy -0.20828 -0.13335) (xy -0.21971 -0.10287) (xy -0.22225 -0.09271) (xy -0.22479 -0.08128) (xy -0.22606 -0.07112)
						(xy -0.2286 -0.05969) (xy -0.2286 -0.01651) (xy -0.22606 -0.00508) (xy -0.22479 0.00508) (xy -0.22225 0.01651)
						(xy -0.21971 0.02667) (xy -0.20828 0.05715) (xy -0.19812 0.07747) (xy -0.19177 0.08636) (xy -0.18669 0.09525)
						(xy -0.17907 0.10414) (xy -0.17272 0.11303) (xy -0.1651 0.12065) (xy -0.1651 0.7366) (xy -0.16256 0.76835)
						(xy -0.1524 0.8001) (xy -0.13716 0.82804) (xy -0.11684 0.85344) (xy -0.09144 0.87376) (xy -0.0635 0.889)
						(xy -0.03175 0.89916) (xy 0 0.9017) (xy 0.03175 0.89916) (xy 0.0635 0.889) (xy 0.09144 0.87376)
						(xy 0.11684 0.85344) (xy 0.13716 0.82804) (xy 0.1524 0.8001) (xy 0.16256 0.76835) (xy 0.1651 0.7366)
						(xy 0.1651 0.11938) (xy 0.17272 0.11176) (xy 0.19812 0.0762) (xy 0.2032 0.06604) (xy 0.20701 0.05715)
						(xy 0.21209 0.04699) (xy 0.2159 0.03683) (xy 0.21844 0.02667) (xy 0.22225 0.01524) (xy 0.22352 0.00508)
						(xy 0.22606 -0.00508) (xy 0.22733 -0.01651) (xy 0.22733 -0.02667) (xy 0.2286 -0.0381) (xy 0.22733 -0.04953)
						(xy 0.22733 -0.05969) (xy 0.22606 -0.07112) (xy 0.22352 -0.08128) (xy 0.22225 -0.09144) (xy 0.21844 -0.10287)
						(xy 0.2159 -0.11303) (xy 0.21209 -0.12319) (xy 0.20701 -0.13335) (xy 0.2032 -0.14224) (xy 0.19812 -0.1524)
						(xy 0.17272 -0.18796) (xy 0.1651 -0.19558) (xy 0.1651 -0.7366) (xy 0.16256 -0.76835) (xy 0.1524 -0.8001)
						(xy 0.13716 -0.82804) (xy 0.11684 -0.85344) (xy 0.09144 -0.87376) (xy 0.0635 -0.889) (xy 0.03175 -0.89916)
					)
					(width 0)
					(fill yes)
				)
			)
		)
		(pad "148" smd custom
			(at 14.85011 4.100068 180)
			(size 0.1143 0.1143)
			(layers "B.Cu" "B.Mask" "B.Paste")
			(net "M_B_DQ44")
			(options
				(clearance outline)
				(anchor circle)
			)
			(primitives
				(gr_poly
					(pts
						(xy 0 -0.9017) (xy -0.03175 -0.89916) (xy -0.0635 -0.889) (xy -0.09144 -0.87376) (xy -0.11684 -0.85344)
						(xy -0.13716 -0.82804) (xy -0.1524 -0.8001) (xy -0.16256 -0.76835) (xy -0.1651 -0.7366) (xy -0.1651 -0.11938)
						(xy -0.17272 -0.11176) (xy -0.19812 -0.0762) (xy -0.2032 -0.06604) (xy -0.20701 -0.05715) (xy -0.21209 -0.04699)
						(xy -0.2159 -0.03683) (xy -0.21844 -0.02667) (xy -0.22225 -0.01524) (xy -0.22352 -0.00508) (xy -0.22606 0.00508)
						(xy -0.22733 0.01651) (xy -0.22733 0.02667) (xy -0.2286 0.0381) (xy -0.22733 0.04953) (xy -0.22733 0.05969)
						(xy -0.22606 0.07112) (xy -0.22352 0.08128) (xy -0.22225 0.09144) (xy -0.21844 0.10287) (xy -0.2159 0.11303)
						(xy -0.21209 0.12319) (xy -0.20701 0.13335) (xy -0.2032 0.14224) (xy -0.19812 0.1524) (xy -0.17272 0.18796)
						(xy -0.1651 0.19558) (xy -0.1651 0.7366) (xy -0.16256 0.76835) (xy -0.1524 0.8001) (xy -0.13716 0.82804)
						(xy -0.11684 0.85344) (xy -0.09144 0.87376) (xy -0.0635 0.889) (xy -0.03175 0.89916) (xy 0 0.9017)
						(xy 0.03175 0.89916) (xy 0.0635 0.889) (xy 0.09144 0.87376) (xy 0.11684 0.85344) (xy 0.13716 0.82804)
						(xy 0.1524 0.8001) (xy 0.16256 0.76835) (xy 0.1651 0.7366) (xy 0.1651 0.19685) (xy 0.17272 0.18923)
						(xy 0.17907 0.18034) (xy 0.18669 0.17145) (xy 0.19177 0.16256) (xy 0.19812 0.15367) (xy 0.20828 0.13335)
						(xy 0.21971 0.10287) (xy 0.22225 0.09271) (xy 0.22479 0.08128) (xy 0.22606 0.07112) (xy 0.2286 0.05969)
						(xy 0.2286 0.01651) (xy 0.22606 0.00508) (xy 0.22479 -0.00508) (xy 0.22225 -0.01651) (xy 0.21971 -0.02667)
						(xy 0.20828 -0.05715) (xy 0.19812 -0.07747) (xy 0.19177 -0.08636) (xy 0.18669 -0.09525) (xy 0.17907 -0.10414)
						(xy 0.17272 -0.11303) (xy 0.1651 -0.12065) (xy 0.1651 -0.7366) (xy 0.16256 -0.76835) (xy 0.1524 -0.8001)
						(xy 0.13716 -0.82804) (xy 0.11684 -0.85344) (xy 0.09144 -0.87376) (xy 0.0635 -0.889) (xy 0.03175 -0.89916)
					)
					(width 0)
					(fill yes)
				)
			)
		)
		(pad "149" smd custom
			(at 15.150084 -4.100068 180)
			(size 0.1143 0.1143)
			(layers "B.Cu" "B.Mask" "B.Paste")
			(net "GND")
			(options
				(clearance outline)
				(anchor circle)
			)
			(primitives
				(gr_poly
					(pts
						(xy 0 -0.9017) (xy -0.03175 -0.89916) (xy -0.0635 -0.889) (xy -0.09144 -0.87376) (xy -0.11684 -0.85344)
						(xy -0.13716 -0.82804) (xy -0.1524 -0.8001) (xy -0.16256 -0.76835) (xy -0.1651 -0.7366) (xy -0.1651 -0.44958)
						(xy -0.17272 -0.44196) (xy -0.19812 -0.4064) (xy -0.2032 -0.39624) (xy -0.20701 -0.38735) (xy -0.21209 -0.37719)
						(xy -0.2159 -0.36703) (xy -0.21844 -0.35687) (xy -0.22225 -0.34544) (xy -0.22352 -0.33528) (xy -0.22606 -0.32512)
						(xy -0.22733 -0.31369) (xy -0.22733 -0.30353) (xy -0.2286 -0.2921) (xy -0.22733 -0.28067) (xy -0.22733 -0.27051)
						(xy -0.22606 -0.25908) (xy -0.22352 -0.24892) (xy -0.22225 -0.23876) (xy -0.21844 -0.22733) (xy -0.2159 -0.21717)
						(xy -0.21209 -0.20701) (xy -0.20701 -0.19685) (xy -0.2032 -0.18796) (xy -0.19812 -0.1778) (xy -0.17272 -0.14224)
						(xy -0.1651 -0.13462) (xy -0.1651 0.7366) (xy -0.16256 0.76835) (xy -0.1524 0.8001) (xy -0.13716 0.82804)
						(xy -0.11684 0.85344) (xy -0.09144 0.87376) (xy -0.0635 0.889) (xy -0.03175 0.89916) (xy 0 0.9017)
						(xy 0.03175 0.89916) (xy 0.0635 0.889) (xy 0.09144 0.87376) (xy 0.11684 0.85344) (xy 0.13716 0.82804)
						(xy 0.1524 0.8001) (xy 0.16256 0.76835) (xy 0.1651 0.7366) (xy 0.1651 -0.13462) (xy 0.17272 -0.14224)
						(xy 0.19812 -0.1778) (xy 0.2032 -0.18796) (xy 0.20701 -0.19685) (xy 0.21209 -0.20701) (xy 0.2159 -0.21717)
						(xy 0.21844 -0.22733) (xy 0.22225 -0.23876) (xy 0.22352 -0.24892) (xy 0.22606 -0.25908) (xy 0.22733 -0.27051)
						(xy 0.22733 -0.28067) (xy 0.2286 -0.2921) (xy 0.22733 -0.30353) (xy 0.22733 -0.31369) (xy 0.22606 -0.32512)
						(xy 0.22352 -0.33528) (xy 0.22225 -0.34544) (xy 0.21844 -0.35687) (xy 0.2159 -0.36703) (xy 0.21209 -0.37719)
						(xy 0.20701 -0.38735) (xy 0.2032 -0.39624) (xy 0.19812 -0.4064) (xy 0.17272 -0.44196) (xy 0.1651 -0.44958)
						(xy 0.1651 -0.7366) (xy 0.16256 -0.76835) (xy 0.1524 -0.8001) (xy 0.13716 -0.82804) (xy 0.11684 -0.85344)
						(xy 0.09144 -0.87376) (xy 0.0635 -0.889) (xy 0.03175 -0.89916)
					)
					(width 0)
					(fill yes)
				)
			)
		)
		(pad "150" smd custom
			(at 15.450058 4.100068 180)
			(size 0.1143 0.1143)
			(layers "B.Cu" "B.Mask" "B.Paste")
			(net "M_B_DQ45")
			(options
				(clearance outline)
				(anchor circle)
			)
			(primitives
				(gr_poly
					(pts
						(xy 0 -0.9017) (xy -0.03175 -0.89916) (xy -0.0635 -0.889) (xy -0.09144 -0.87376) (xy -0.11684 -0.85344)
						(xy -0.13716 -0.82804) (xy -0.1524 -0.8001) (xy -0.16256 -0.76835) (xy -0.1651 -0.7366) (xy -0.1651 0.13462)
						(xy -0.17272 0.14224) (xy -0.19812 0.1778) (xy -0.2032 0.18796) (xy -0.20701 0.19685) (xy -0.21209 0.20701)
						(xy -0.2159 0.21717) (xy -0.21844 0.22733) (xy -0.22225 0.23876) (xy -0.22352 0.24892) (xy -0.22606 0.25908)
						(xy -0.22733 0.27051) (xy -0.22733 0.28067) (xy -0.2286 0.2921) (xy -0.22733 0.30353) (xy -0.22733 0.31369)
						(xy -0.22606 0.32512) (xy -0.22352 0.33528) (xy -0.22225 0.34544) (xy -0.21844 0.35687) (xy -0.2159 0.36703)
						(xy -0.21209 0.37719) (xy -0.20701 0.38735) (xy -0.2032 0.39624) (xy -0.19812 0.4064) (xy -0.17272 0.44196)
						(xy -0.1651 0.44958) (xy -0.1651 0.7366) (xy -0.16256 0.76835) (xy -0.1524 0.8001) (xy -0.13716 0.82804)
						(xy -0.11684 0.85344) (xy -0.09144 0.87376) (xy -0.0635 0.889) (xy -0.03175 0.89916) (xy 0 0.9017)
						(xy 0.03175 0.89916) (xy 0.0635 0.889) (xy 0.09144 0.87376) (xy 0.11684 0.85344) (xy 0.13716 0.82804)
						(xy 0.1524 0.8001) (xy 0.16256 0.76835) (xy 0.1651 0.7366) (xy 0.1651 0.44958) (xy 0.17272 0.44196)
						(xy 0.19812 0.4064) (xy 0.2032 0.39624) (xy 0.20701 0.38735) (xy 0.21209 0.37719) (xy 0.2159 0.36703)
						(xy 0.21844 0.35687) (xy 0.22225 0.34544) (xy 0.22352 0.33528) (xy 0.22606 0.32512) (xy 0.22733 0.31369)
						(xy 0.22733 0.30353) (xy 0.2286 0.2921) (xy 0.22733 0.28067) (xy 0.22733 0.27051) (xy 0.22606 0.25908)
						(xy 0.22352 0.24892) (xy 0.22225 0.23876) (xy 0.21844 0.22733) (xy 0.2159 0.21717) (xy 0.21209 0.20701)
						(xy 0.20701 0.19685) (xy 0.2032 0.18796) (xy 0.19812 0.1778) (xy 0.17272 0.14224) (xy 0.1651 0.13462)
						(xy 0.1651 -0.7366) (xy 0.16256 -0.76835) (xy 0.1524 -0.8001) (xy 0.13716 -0.82804) (xy 0.11684 -0.85344)
						(xy 0.09144 -0.87376) (xy 0.0635 -0.889) (xy 0.03175 -0.89916)
					)
					(width 0)
					(fill yes)
				)
			)
		)
		(pad "151" smd custom
			(at 15.750032 -4.100068 180)
			(size 0.1143 0.1143)
			(layers "B.Cu" "B.Mask" "B.Paste")
			(net "M_B_DQ40")
			(options
				(clearance outline)
				(anchor circle)
			)
			(primitives
				(gr_poly
					(pts
						(xy 0 -0.9017) (xy -0.03175 -0.89916) (xy -0.0635 -0.889) (xy -0.09144 -0.87376) (xy -0.11684 -0.85344)
						(xy -0.13716 -0.82804) (xy -0.1524 -0.8001) (xy -0.16256 -0.76835) (xy -0.1651 -0.7366) (xy -0.1651 -0.19685)
						(xy -0.17272 -0.18923) (xy -0.17907 -0.18034) (xy -0.18669 -0.17145) (xy -0.19177 -0.16256) (xy -0.19812 -0.15367)
						(xy -0.20828 -0.13335) (xy -0.21971 -0.10287) (xy -0.22225 -0.09271) (xy -0.22479 -0.08128) (xy -0.22606 -0.07112)
						(xy -0.2286 -0.05969) (xy -0.2286 -0.01651) (xy -0.22606 -0.00508) (xy -0.22479 0.00508) (xy -0.22225 0.01651)
						(xy -0.21971 0.02667) (xy -0.20828 0.05715) (xy -0.19812 0.07747) (xy -0.19177 0.08636) (xy -0.18669 0.09525)
						(xy -0.17907 0.10414) (xy -0.17272 0.11303) (xy -0.1651 0.12065) (xy -0.1651 0.7366) (xy -0.16256 0.76835)
						(xy -0.1524 0.8001) (xy -0.13716 0.82804) (xy -0.11684 0.85344) (xy -0.09144 0.87376) (xy -0.0635 0.889)
						(xy -0.03175 0.89916) (xy 0 0.9017) (xy 0.03175 0.89916) (xy 0.0635 0.889) (xy 0.09144 0.87376)
						(xy 0.11684 0.85344) (xy 0.13716 0.82804) (xy 0.1524 0.8001) (xy 0.16256 0.76835) (xy 0.1651 0.7366)
						(xy 0.1651 0.11938) (xy 0.17272 0.11176) (xy 0.19812 0.0762) (xy 0.2032 0.06604) (xy 0.20701 0.05715)
						(xy 0.21209 0.04699) (xy 0.2159 0.03683) (xy 0.21844 0.02667) (xy 0.22225 0.01524) (xy 0.22352 0.00508)
						(xy 0.22606 -0.00508) (xy 0.22733 -0.01651) (xy 0.22733 -0.02667) (xy 0.2286 -0.0381) (xy 0.22733 -0.04953)
						(xy 0.22733 -0.05969) (xy 0.22606 -0.07112) (xy 0.22352 -0.08128) (xy 0.22225 -0.09144) (xy 0.21844 -0.10287)
						(xy 0.2159 -0.11303) (xy 0.21209 -0.12319) (xy 0.20701 -0.13335) (xy 0.2032 -0.14224) (xy 0.19812 -0.1524)
						(xy 0.17272 -0.18796) (xy 0.1651 -0.19558) (xy 0.1651 -0.7366) (xy 0.16256 -0.76835) (xy 0.1524 -0.8001)
						(xy 0.13716 -0.82804) (xy 0.11684 -0.85344) (xy 0.09144 -0.87376) (xy 0.0635 -0.889) (xy 0.03175 -0.89916)
					)
					(width 0)
					(fill yes)
				)
			)
		)
		(pad "152" smd custom
			(at 16.050006 4.100068 180)
			(size 0.1143 0.1143)
			(layers "B.Cu" "B.Mask" "B.Paste")
			(net "GND")
			(options
				(clearance outline)
				(anchor circle)
			)
			(primitives
				(gr_poly
					(pts
						(xy 0 -0.9017) (xy -0.03175 -0.89916) (xy -0.0635 -0.889) (xy -0.09144 -0.87376) (xy -0.11684 -0.85344)
						(xy -0.13716 -0.82804) (xy -0.1524 -0.8001) (xy -0.16256 -0.76835) (xy -0.1651 -0.7366) (xy -0.1651 -0.11938)
						(xy -0.17272 -0.11176) (xy -0.19812 -0.0762) (xy -0.2032 -0.06604) (xy -0.20701 -0.05715) (xy -0.21209 -0.04699)
						(xy -0.2159 -0.03683) (xy -0.21844 -0.02667) (xy -0.22225 -0.01524) (xy -0.22352 -0.00508) (xy -0.22606 0.00508)
						(xy -0.22733 0.01651) (xy -0.22733 0.02667) (xy -0.2286 0.0381) (xy -0.22733 0.04953) (xy -0.22733 0.05969)
						(xy -0.22606 0.07112) (xy -0.22352 0.08128) (xy -0.22225 0.09144) (xy -0.21844 0.10287) (xy -0.2159 0.11303)
						(xy -0.21209 0.12319) (xy -0.20701 0.13335) (xy -0.2032 0.14224) (xy -0.19812 0.1524) (xy -0.17272 0.18796)
						(xy -0.1651 0.19558) (xy -0.1651 0.7366) (xy -0.16256 0.76835) (xy -0.1524 0.8001) (xy -0.13716 0.82804)
						(xy -0.11684 0.85344) (xy -0.09144 0.87376) (xy -0.0635 0.889) (xy -0.03175 0.89916) (xy 0 0.9017)
						(xy 0.03175 0.89916) (xy 0.0635 0.889) (xy 0.09144 0.87376) (xy 0.11684 0.85344) (xy 0.13716 0.82804)
						(xy 0.1524 0.8001) (xy 0.16256 0.76835) (xy 0.1651 0.7366) (xy 0.1651 0.19685) (xy 0.17272 0.18923)
						(xy 0.17907 0.18034) (xy 0.18669 0.17145) (xy 0.19177 0.16256) (xy 0.19812 0.15367) (xy 0.20828 0.13335)
						(xy 0.21971 0.10287) (xy 0.22225 0.09271) (xy 0.22479 0.08128) (xy 0.22606 0.07112) (xy 0.2286 0.05969)
						(xy 0.2286 0.01651) (xy 0.22606 0.00508) (xy 0.22479 -0.00508) (xy 0.22225 -0.01651) (xy 0.21971 -0.02667)
						(xy 0.20828 -0.05715) (xy 0.19812 -0.07747) (xy 0.19177 -0.08636) (xy 0.18669 -0.09525) (xy 0.17907 -0.10414)
						(xy 0.17272 -0.11303) (xy 0.1651 -0.12065) (xy 0.1651 -0.7366) (xy 0.16256 -0.76835) (xy 0.1524 -0.8001)
						(xy 0.13716 -0.82804) (xy 0.11684 -0.85344) (xy 0.09144 -0.87376) (xy 0.0635 -0.889) (xy 0.03175 -0.89916)
					)
					(width 0)
					(fill yes)
				)
			)
		)
		(pad "153" smd custom
			(at 16.34998 -4.100068 180)
			(size 0.1143 0.1143)
			(layers "B.Cu" "B.Mask" "B.Paste")
			(net "M_B_DQ41")
			(options
				(clearance outline)
				(anchor circle)
			)
			(primitives
				(gr_poly
					(pts
						(xy 0 -0.9017) (xy -0.03175 -0.89916) (xy -0.0635 -0.889) (xy -0.09144 -0.87376) (xy -0.11684 -0.85344)
						(xy -0.13716 -0.82804) (xy -0.1524 -0.8001) (xy -0.16256 -0.76835) (xy -0.1651 -0.7366) (xy -0.1651 -0.44958)
						(xy -0.17272 -0.44196) (xy -0.19812 -0.4064) (xy -0.2032 -0.39624) (xy -0.20701 -0.38735) (xy -0.21209 -0.37719)
						(xy -0.2159 -0.36703) (xy -0.21844 -0.35687) (xy -0.22225 -0.34544) (xy -0.22352 -0.33528) (xy -0.22606 -0.32512)
						(xy -0.22733 -0.31369) (xy -0.22733 -0.30353) (xy -0.2286 -0.2921) (xy -0.22733 -0.28067) (xy -0.22733 -0.27051)
						(xy -0.22606 -0.25908) (xy -0.22352 -0.24892) (xy -0.22225 -0.23876) (xy -0.21844 -0.22733) (xy -0.2159 -0.21717)
						(xy -0.21209 -0.20701) (xy -0.20701 -0.19685) (xy -0.2032 -0.18796) (xy -0.19812 -0.1778) (xy -0.17272 -0.14224)
						(xy -0.1651 -0.13462) (xy -0.1651 0.7366) (xy -0.16256 0.76835) (xy -0.1524 0.8001) (xy -0.13716 0.82804)
						(xy -0.11684 0.85344) (xy -0.09144 0.87376) (xy -0.0635 0.889) (xy -0.03175 0.89916) (xy 0 0.9017)
						(xy 0.03175 0.89916) (xy 0.0635 0.889) (xy 0.09144 0.87376) (xy 0.11684 0.85344) (xy 0.13716 0.82804)
						(xy 0.1524 0.8001) (xy 0.16256 0.76835) (xy 0.1651 0.7366) (xy 0.1651 -0.13462) (xy 0.17272 -0.14224)
						(xy 0.19812 -0.1778) (xy 0.2032 -0.18796) (xy 0.20701 -0.19685) (xy 0.21209 -0.20701) (xy 0.2159 -0.21717)
						(xy 0.21844 -0.22733) (xy 0.22225 -0.23876) (xy 0.22352 -0.24892) (xy 0.22606 -0.25908) (xy 0.22733 -0.27051)
						(xy 0.22733 -0.28067) (xy 0.2286 -0.2921) (xy 0.22733 -0.30353) (xy 0.22733 -0.31369) (xy 0.22606 -0.32512)
						(xy 0.22352 -0.33528) (xy 0.22225 -0.34544) (xy 0.21844 -0.35687) (xy 0.2159 -0.36703) (xy 0.21209 -0.37719)
						(xy 0.20701 -0.38735) (xy 0.2032 -0.39624) (xy 0.19812 -0.4064) (xy 0.17272 -0.44196) (xy 0.1651 -0.44958)
						(xy 0.1651 -0.7366) (xy 0.16256 -0.76835) (xy 0.1524 -0.8001) (xy 0.13716 -0.82804) (xy 0.11684 -0.85344)
						(xy 0.09144 -0.87376) (xy 0.0635 -0.889) (xy 0.03175 -0.89916)
					)
					(width 0)
					(fill yes)
				)
			)
		)
	)
)
